FILE_TYPE = MULTI_PHYS_TABLE;

PART 'INA230AIRGTR'

{========================================================================================}
:VALUE          | PART_TYPE | MATERIAL | PART_NUMBER    = STANDARD    | LIFECYCLE      | PART_NUMBER   | JEDEC_TYPE   | DESCRIPTION                             | MANUFTR | MANUF_PN       | RD_CMPLS_LVL | CMPLS_LVL | FROM_PJ     | CLASS | DIP_SMD | DATA                     | EE_CHECK_LIST | FP_ECN | PSL | CREATOR | STATUS | MSD | ESD_CDM | ESD_HBM | ESD_MM | PIN_LENGTH_SHORT_PIN | PIN_LENGTH_LONG_PIN | CREATEDAY  ;
{========================================================================================}
 'INA230AIRGTR' | 'SMLF'    | 'IC'     | 'AL000230001'(!) = ''               | ''               | 'AL000230001' |'QFN16_THXI'| 'IC OTHER (16P) INA230AIRGTR (QFN 3X3)' | 'TIC'   | 'INA230AIRGTR' | 'EP(V1)'     | 'EP(V1)'  | 'F07-HENRY' | 'IC'  | ''      | 'TIC_INA230_REV2012.pdf' | ''            | ''     | ''  | ''      | ''     | ''  | ''      | ''      | ''     | ''                   | ''                  | '20170914'
 'INA230AIRGTR' | 'SMLF'    | 'EMPTY'  | 'AL000230001'(!) = ''               | ''               | 'AL000230001' |'QFN16_THXI'| 'IC OTHER (16P) INA230AIRGTR (QFN 3X3)' | 'TIC'   | 'INA230AIRGTR' | 'EP(V1)'     | 'EP(V1)'  | 'F07-HENRY' | 'IC'  | ''      | 'TIC_INA230_REV2012.pdf' | ''            | ''     | ''  | ''      | ''     | ''  | ''      | ''      | ''     | ''                   | ''                  | '20170914'

END_PART

END.

